# BASEBOARD_FAB2 (Tioga Pass) — schematic netlist excerpt (pin names and nets, part order shuffled) for the footprints in the layout excerpt that follows; sources: Cadence DE-HDL packaged netlist, KiCad conversion of Wiwynn_Tioga_Pass_MB.brd

R8G21  RES  0.0 5% CHIP  pkg 0402  page 189 : A = JTAG_TMS ; B = JTAG_TMS_R
R1B5  RES  22.1 1.0% CHIP  pkg 0402  page 226 : A = PWRGD_PVDDQ_KLM_R ; B = PWRGD_PVDDQ_KLM
CT21  CAP_A  0.1UF 16V 10% X7R  pkg 0402V  page 208 : A = VR_PVCCIN_CPU1_AIREF4 ; B = GND

(kicad_pcb
	(version 20260206)
	(generator "pcbnew")
	(generator_version "10.0")
	(general
		(thickness 1.6)
		(legacy_teardrops no)
	)
	(paper "A4")
	(title_block
		(title "Wiwynn_Tioga_Pass_MB.brd")
		(comment 1 "Tioga Pass / footprints 559-561 of 4770")
	)
	(layers
		(0 "F.Cu" signal "TOP")
		(4 "In1.Cu" signal "L2GND")
		(6 "In2.Cu" signal "L3")
		(8 "In3.Cu" signal "L4GND")
		(10 "In4.Cu" signal "L5")
		(12 "In5.Cu" signal "L6GND")
		(14 "In6.Cu" signal "L7VCC")
		(16 "In7.Cu" signal "L8VCC")
		(18 "In8.Cu" signal "L9GND")
		(20 "In9.Cu" signal "L10")
		(22 "In10.Cu" signal "L11GND")
		(24 "In11.Cu" signal "L12")
		(26 "In12.Cu" signal "L13GND")
		(2 "B.Cu" signal "BOTTOM")
		(9 "F.Adhes" user "F.Adhesive")
		(11 "B.Adhes" user "B.Adhesive")
		(13 "F.Paste" user "Package Geometry/Pastemask Top")
		(15 "B.Paste" user "Package Geometry/Pastemask Bottom")
		(5 "F.SilkS" user "Ref Des/Silkscreen Top")
		(7 "B.SilkS" user "Ref Des/Silkscreen Bottom")
		(1 "F.Mask" user "Board Geometry/Soldermask Top")
		(3 "B.Mask" user "Board Geometry/Soldermask Bottom")
		(17 "Dwgs.User" user "User.Drawings")
		(19 "Cmts.User" user "User.Comments")
		(21 "Eco1.User" user "User.Eco1")
		(23 "Eco2.User" user "User.Eco2")
		(25 "Edge.Cuts" user "Board Geometry/Outline")
		(27 "Margin" user)
		(31 "F.CrtYd" user "Package Geometry/Place Bound Top")
		(29 "B.CrtYd" user "Package Geometry/Place Bound Bottom")
		(35 "F.Fab" user "Ref Des/Assembly Top")
		(33 "B.Fab" user "Ref Des/Assembly Bottom")
	)
	(footprint ""
		(layer "F.Cu")
		(at -1.41986 -131.65836 180)
		(property "Reference" "R1B5"
			(at 0 0 180)
			(layer "F.SilkS")
			(hide yes)
			(effects
				(font
					(size 1.27 1.27)
				)
			)
		)
		(property "Value" ""
			(at 0 0 180)
			(layer "F.Fab")
			(effects
				(font
					(size 1.27 1.27)
				)
			)
		)
		(duplicate_pad_numbers_are_jumpers no)
		(fp_rect
			(start 0.2794 -0.1016)
			(end -0.2794 0.9906)
			(stroke
				(width 0)
				(type default)
			)
			(fill no)
			(layer "F.CrtYd")
		)
		(fp_line
			(start 0.2794 0.9906)
			(end 0.2794 -0.1016)
			(stroke
				(width 0.1)
				(type default)
			)
			(layer "F.Fab")
		)
		(fp_line
			(start 0.2794 -0.1016)
			(end -0.2794 -0.1016)
			(stroke
				(width 0.1)
				(type default)
			)
			(layer "F.Fab")
		)
		(fp_line
			(start -0.2794 0.9906)
			(end 0.2794 0.9906)
			(stroke
				(width 0.1)
				(type default)
			)
			(layer "F.Fab")
		)
		(fp_line
			(start -0.2794 -0.1016)
			(end -0.2794 0.9906)
			(stroke
				(width 0.1)
				(type default)
			)
			(layer "F.Fab")
		)
		(pad "1" smd rect
			(at 0 0 180)
			(size 0.508 0.508)
			(layers "F.Cu" "F.Mask" "F.Paste")
			(net "PWRGD_PVDDQ_KLM_R")
		)
		(pad "2" smd rect
			(at 0 0.889 180)
			(size 0.508 0.508)
			(layers "F.Cu" "F.Mask" "F.Paste")
			(net "PWRGD_PVDDQ_KLM")
		)
		(zone
			(layer "F.Cu")
			(hatch none 0.5)
			(connect_pads
				(clearance 0)
			)
			(min_thickness 0.25)
			(keepout
				(tracks not_allowed)
				(vias allowed)
				(pads allowed)
				(copperpour not_allowed)
				(footprints allowed)
			)
			(placement
				(enabled no)
				(sheetname "")
			)
			(fill
				(thermal_gap 0.5)
				(thermal_bridge_width 0.5)
				(island_removal_mode 0)
			)
			(polygon
				(pts
					(xy -1.67386 -131.91236) (xy -1.16586 -131.91236) (xy -1.16586 -132.29336) (xy -1.67386 -132.29336)
				)
			)
		)
		(zone
			(layer "F.Cu")
			(hatch none 0.5)
			(connect_pads
				(clearance 0)
			)
			(min_thickness 0.25)
			(keepout
				(tracks allowed)
				(vias not_allowed)
				(pads allowed)
				(copperpour not_allowed)
				(footprints allowed)
			)
			(placement
				(enabled no)
				(sheetname "")
			)
			(fill
				(thermal_gap 0.5)
				(thermal_bridge_width 0.5)
				(island_removal_mode 0)
			)
			(polygon
				(pts
					(xy -1.67386 -131.91236) (xy -1.16586 -131.91236) (xy -1.16586 -132.29336) (xy -1.67386 -132.29336)
				)
			)
		)
	)
	(footprint ""
		(layer "F.Cu")
		(at 30.013656 -78.33741)
		(property "Reference" "CT21"
			(at -0.88773 0.5842 90)
			(unlocked yes)
			(layer "F.SilkS")
			(effects
				(font
					(size 0.7874 0.5842)
					(thickness 0.1524)
				)
				(justify left)
			)
		)
		(property "Value" ""
			(at 0 0 0)
			(layer "F.Fab")
			(effects
				(font
					(size 1.27 1.27)
				)
			)
		)
		(duplicate_pad_numbers_are_jumpers no)
		(fp_poly
			(pts
				(xy 0.3048 -0.1016) (xy 0.3048 0.9906) (xy -0.3048 0.9906) (xy -0.3048 -0.1016)
			)
			(stroke
				(width 0)
				(type default)
			)
			(fill no)
			(layer "F.CrtYd")
		)
		(fp_line
			(start -0.3048 -0.1016)
			(end -0.3048 0.9906)
			(stroke
				(width 0.1)
				(type default)
			)
			(layer "F.Fab")
		)
		(fp_line
			(start -0.3048 0.9906)
			(end 0.3048 0.9906)
			(stroke
				(width 0.1)
				(type default)
			)
			(layer "F.Fab")
		)
		(fp_line
			(start 0.3048 -0.1016)
			(end -0.3048 -0.1016)
			(stroke
				(width 0.1)
				(type default)
			)
			(layer "F.Fab")
		)
		(fp_line
			(start 0.3048 0.9906)
			(end 0.3048 -0.1016)
			(stroke
				(width 0.1)
				(type default)
			)
			(layer "F.Fab")
		)
		(pad "1" smd rect
			(at 0 0)
			(size 0.508 0.508)
			(layers "F.Cu" "F.Mask" "F.Paste")
			(net "VR_PVCCIN_CPU1_AIREF4")
		)
		(pad "2" smd rect
			(at 0 0.889)
			(size 0.508 0.508)
			(layers "F.Cu" "F.Mask" "F.Paste")
			(net "GND")
		)
		(zone
			(layer "F.Cu")
			(hatch none 0.5)
			(connect_pads
				(clearance 0)
			)
			(min_thickness 0.25)
			(keepout
				(tracks allowed)
				(vias not_allowed)
				(pads allowed)
				(copperpour not_allowed)
				(footprints allowed)
			)
			(placement
				(enabled no)
				(sheetname "")
			)
			(fill
				(thermal_gap 0.5)
				(thermal_bridge_width 0.5)
				(island_removal_mode 0)
			)
			(polygon
				(pts
					(xy 29.759656 -78.08341) (xy 30.267656 -78.08341) (xy 30.267656 -77.70241) (xy 29.759656 -77.70241)
				)
			)
		)
		(zone
			(layer "F.Cu")
			(hatch none 0.5)
			(connect_pads
				(clearance 0)
			)
			(min_thickness 0.25)
			(keepout
				(tracks not_allowed)
				(vias allowed)
				(pads allowed)
				(copperpour not_allowed)
				(footprints allowed)
			)
			(placement
				(enabled no)
				(sheetname "")
			)
			(fill
				(thermal_gap 0.5)
				(thermal_bridge_width 0.5)
				(island_removal_mode 0)
			)
			(polygon
				(pts
					(xy 29.759656 -77.70241) (xy 30.267656 -77.70241) (xy 30.267656 -78.08341) (xy 29.759656 -78.08341)
				)
			)
		)
	)
	(footprint ""
		(layer "F.Cu")
		(at 395.6812 1.5748 -90)
		(property "Reference" "R8G21"
			(at 0 0 270)
			(layer "F.SilkS")
			(hide yes)
			(effects
				(font
					(size 1.27 1.27)
				)
			)
		)
		(property "Value" ""
			(at 0 0 270)
			(layer "F.Fab")
			(effects
				(font
					(size 1.27 1.27)
				)
			)
		)
		(duplicate_pad_numbers_are_jumpers no)
		(fp_poly
			(pts
				(xy -0.2794 -0.1016) (xy 0.2794 -0.1016) (xy 0.2794 0.9906) (xy -0.2794 0.9906)
			)
			(stroke
				(width 0)
				(type default)
			)
			(fill no)
			(layer "F.CrtYd")
		)
		(fp_line
			(start -0.2794 0.9906)
			(end 0.2794 0.9906)
			(stroke
				(width 0.1)
				(type default)
			)
			(layer "F.Fab")
		)
		(fp_line
			(start 0.2794 0.9906)
			(end 0.2794 -0.1016)
			(stroke
				(width 0.1)
				(type default)
			)
			(layer "F.Fab")
		)
		(fp_line
			(start -0.2794 -0.1016)
			(end -0.2794 0.9906)
			(stroke
				(width 0.1)
				(type default)
			)
			(layer "F.Fab")
		)
		(fp_line
			(start 0.2794 -0.1016)
			(end -0.2794 -0.1016)
			(stroke
				(width 0.1)
				(type default)
			)
			(layer "F.Fab")
		)
		(pad "1" smd rect
			(at 0 0 270)
			(size 0.508 0.508)
			(layers "F.Cu" "F.Mask" "F.Paste")
			(net "JTAG_TMS")
		)
		(pad "2" smd rect
			(at 0 0.889 270)
			(size 0.508 0.508)
			(layers "F.Cu" "F.Mask" "F.Paste")
			(net "JTAG_TMS_R")
		)
		(zone
			(layer "F.Cu")
			(hatch none 0.5)
			(connect_pads
				(clearance 0)
			)
			(min_thickness 0.25)
			(keepout
				(tracks not_allowed)
				(vias allowed)
				(pads allowed)
				(copperpour not_allowed)
				(footprints allowed)
			)
			(placement
				(enabled no)
				(sheetname "")
			)
			(fill
				(thermal_gap 0.5)
				(thermal_bridge_width 0.5)
				(island_removal_mode 0)
			)
			(polygon
				(pts
					(xy 395.0462 1.3208) (xy 395.0462 1.8288) (xy 395.4272 1.8288) (xy 395.4272 1.3208)
				)
			)
		)
		(zone
			(layer "F.Cu")
			(hatch none 0.5)
			(connect_pads
				(clearance 0)
			)
			(min_thickness 0.25)
			(keepout
				(tracks allowed)
				(vias not_allowed)
				(pads allowed)
				(copperpour not_allowed)
				(footprints allowed)
			)
			(placement
				(enabled no)
				(sheetname "")
			)
			(fill
				(thermal_gap 0.5)
				(thermal_bridge_width 0.5)
				(island_removal_mode 0)
			)
			(polygon
				(pts
					(xy 395.4272 1.3208) (xy 395.4272 1.8288) (xy 395.0462 1.8288) (xy 395.0462 1.3208)
				)
			)
		)
	)
)
